(kicad_pcb
	(version 20260206)
	(generator "pcbnew")
	(generator_version "10.0")
	(general
		(thickness 1.6)
		(legacy_teardrops no)
	)
	(paper "A4")
	(title_block
		(title "panther-plus-userver — 13130-1b_20150205.brd")
		(comment 1 "Honey Badger (Wiwynn) / footprints 950-957 of 1509")
	)
	(layers
		(0 "F.Cu" signal "TOP")
		(4 "In1.Cu" signal "L2")
		(6 "In2.Cu" signal "L3")
		(8 "In3.Cu" signal "L4")
		(10 "In4.Cu" signal "L5")
		(12 "In5.Cu" signal "L6")
		(14 "In6.Cu" signal "L7")
		(16 "In7.Cu" signal "L8")
		(18 "In8.Cu" signal "L9")
		(20 "In9.Cu" signal "L10")
		(22 "In10.Cu" signal "L11")
		(2 "B.Cu" signal "BOTTOM")
		(9 "F.Adhes" user "F.Adhesive")
		(11 "B.Adhes" user "B.Adhesive")
		(13 "F.Paste" user "Package Geometry/Pastemask Top")
		(15 "B.Paste" user "Package Geometry/Pastemask Bottom")
		(5 "F.SilkS" user "Ref Des/Silkscreen Top")
		(7 "B.SilkS" user "Ref Des/Silkscreen Bottom")
		(1 "F.Mask" user "Board Geometry/Soldermask Top")
		(3 "B.Mask" user "Board Geometry/Soldermask Bottom")
		(17 "Dwgs.User" user "User.Drawings")
		(19 "Cmts.User" user "User.Comments")
		(21 "Eco1.User" user "User.Eco1")
		(23 "Eco2.User" user "User.Eco2")
		(25 "Edge.Cuts" user "Board Geometry/Outline")
		(27 "Margin" user)
		(31 "F.CrtYd" user "Package Geometry/Place Bound Top")
		(29 "B.CrtYd" user "Package Geometry/Place Bound Bottom")
		(35 "F.Fab" user "Ref Des/Assembly Top")
		(33 "B.Fab" user "Ref Des/Assembly Bottom")
	)
	(footprint ""
		(layer "B.Cu")
		(at 112.141 -7.239)
		(property "Reference" "U40"
			(at 0 0 0)
			(layer "B.SilkS")
			(hide yes)
			(effects
				(font
					(size 1.27 1.27)
				)
				(justify mirror)
			)
		)
		(property "Value" "SNLVC1G126DCKR-GP"
			(at 0 -8.0772 0)
			(unlocked yes)
			(layer "B.Fab")
			(hide yes)
			(effects
				(font
					(size 1.016 1.016)
					(thickness 0.1524)
				)
				(justify mirror)
			)
		)
		(property "Device Type" "SC70-5H44"
			(at 0 -9.6012 0)
			(unlocked yes)
			(layer "B.Fab")
			(hide yes)
			(effects
				(font
					(size 1.016 1.016)
					(thickness 0.1524)
				)
				(justify mirror)
			)
		)
		(duplicate_pad_numbers_are_jumpers no)
		(fp_line
			(start -1.0033 -0.3302)
			(end -1.0033 0.3302)
			(stroke
				(width 0.1524)
				(type default)
			)
			(layer "B.SilkS")
		)
		(fp_line
			(start -1.0033 0.3302)
			(end 1.0033 0.3302)
			(stroke
				(width 0.1524)
				(type default)
			)
			(layer "B.SilkS")
		)
		(fp_line
			(start 1.0033 -0.3302)
			(end -1.0033 -0.3302)
			(stroke
				(width 0.1524)
				(type default)
			)
			(layer "B.SilkS")
		)
		(fp_line
			(start 1.0033 0.3302)
			(end 1.0033 -0.3302)
			(stroke
				(width 0.1524)
				(type default)
			)
			(layer "B.SilkS")
		)
		(fp_poly
			(pts
				(xy 1.0033 1.4859) (xy 1.0033 0.8001) (xy 1.1811 0.8001) (xy 1.1811 -0.8001) (xy 1.0033 -0.8001)
				(xy 1.0033 -1.4859) (xy -1.0033 -1.4859) (xy -1.0033 -0.8001) (xy -1.1811 -0.8001) (xy -1.1811 0.8001)
				(xy -1.0033 0.8001) (xy -1.0033 1.4859) (xy -0.2921 1.4859) (xy -0.2921 0.8001) (xy 0.2921 0.8001)
				(xy 0.2921 1.4859)
			)
			(stroke
				(width 0)
				(type default)
			)
			(fill no)
			(layer "B.CrtYd")
		)
		(fp_poly
			(pts
				(xy 1.0033 1.4859) (xy 1.0033 0.8001) (xy 1.1811 0.8001) (xy 1.1811 -0.8001) (xy 1.0033 -0.8001)
				(xy 1.0033 -1.4859) (xy -1.0033 -1.4859) (xy -1.0033 -0.8001) (xy -1.1811 -0.8001) (xy -1.1811 0.8001)
				(xy -1.0033 0.8001) (xy -1.0033 1.4859) (xy -0.2921 1.4859) (xy -0.2921 0.8001) (xy 0.2921 0.8001)
				(xy 0.2921 1.4859)
			)
			(stroke
				(width 0)
				(type default)
			)
			(fill no)
			(layer "B.Fab")
		)
		(pad "1" smd rect
			(at -0.65024 -0.93472 180)
			(size 0.3556 0.762)
			(layers "B.Cu" "B.Mask" "B.Paste")
			(net "PMU_PLTRST#")
		)
		(pad "2" smd rect
			(at 0 -0.93472 180)
			(size 0.3556 0.762)
			(layers "B.Cu" "B.Mask" "B.Paste")
			(net "IRQ_MCERR#")
		)
		(pad "3" smd rect
			(at 0.65024 -0.93472 180)
			(size 0.3556 0.762)
			(layers "B.Cu" "B.Mask" "B.Paste")
			(net "GND")
		)
		(pad "4" smd rect
			(at 0.65024 0.93472 180)
			(size 0.3556 0.762)
			(layers "B.Cu" "B.Mask" "B.Paste")
			(net "IRQ_LV_MCERR#")
		)
		(pad "5" smd rect
			(at -0.65024 0.93472 180)
			(size 0.3556 0.762)
			(layers "B.Cu" "B.Mask" "B.Paste")
			(net "P3V3")
		)
	)
	(footprint ""
		(layer "B.Cu")
		(at 68.834 -46.228)
		(property "Reference" "R294"
			(at 0 0 0)
			(layer "B.SilkS")
			(hide yes)
			(effects
				(font
					(size 1.27 1.27)
				)
				(justify mirror)
			)
		)
		(property "Value" "1KR2F-3-GP"
			(at -0.064008 -3.993896 0)
			(unlocked yes)
			(layer "B.Fab")
			(hide yes)
			(effects
				(font
					(size 1.016 1.016)
					(thickness 0.1524)
				)
				(justify mirror)
			)
		)
		(property "Device Type" "R402H16"
			(at -0.064008 -5.517896 0)
			(unlocked yes)
			(layer "B.Fab")
			(hide yes)
			(effects
				(font
					(size 1.016 1.016)
					(thickness 0.1524)
				)
				(justify mirror)
			)
		)
		(duplicate_pad_numbers_are_jumpers no)
		(fp_rect
			(start 0.381 0.8382)
			(end -0.381 -0.8382)
			(stroke
				(width 0)
				(type default)
			)
			(fill no)
			(layer "B.CrtYd")
		)
		(fp_rect
			(start 0.381 0.8382)
			(end -0.381 -0.8382)
			(stroke
				(width 0)
				(type default)
			)
			(fill no)
			(layer "B.Fab")
		)
		(pad "1" smd custom
			(at 0 -0.4318 180)
			(size 0.127 0.127)
			(layers "B.Cu" "B.Mask" "B.Paste")
			(net "IRQ_NMI_R")
			(options
				(clearance outline)
				(anchor circle)
			)
			(primitives
				(gr_poly
					(pts
						(arc
							(start -0.2032 0.2794)
							(mid -0.239121 0.264521)
							(end -0.254 0.2286)
						)
						(arc
							(start -0.254 -0.2286)
							(mid -0.239121 -0.264521)
							(end -0.2032 -0.2794)
						)
						(arc
							(start 0.2032 -0.2794)
							(mid 0.239121 -0.264521)
							(end 0.254 -0.2286)
						)
						(arc
							(start 0.254 0.2286)
							(mid 0.239121 0.264521)
							(end 0.2032 0.2794)
						)
					)
					(width 0)
					(fill yes)
				)
			)
		)
		(pad "2" smd custom
			(at 0 0.4318 180)
			(size 0.127 0.127)
			(layers "B.Cu" "B.Mask" "B.Paste")
			(net "GND")
			(options
				(clearance outline)
				(anchor circle)
			)
			(primitives
				(gr_poly
					(pts
						(arc
							(start -0.2032 0.2794)
							(mid -0.239121 0.264521)
							(end -0.254 0.2286)
						)
						(arc
							(start -0.254 -0.2286)
							(mid -0.239121 -0.264521)
							(end -0.2032 -0.2794)
						)
						(arc
							(start 0.2032 -0.2794)
							(mid 0.239121 -0.264521)
							(end 0.254 -0.2286)
						)
						(arc
							(start 0.254 0.2286)
							(mid 0.239121 0.264521)
							(end 0.2032 0.2794)
						)
					)
					(width 0)
					(fill yes)
				)
			)
		)
	)
	(footprint ""
		(layer "B.Cu")
		(at 154.9908 -59.5884)
		(property "Reference" "C324"
			(at 0 0 0)
			(layer "B.SilkS")
			(hide yes)
			(effects
				(font
					(size 1.27 1.27)
				)
				(justify mirror)
			)
		)
		(property "Value" "SCD1U16V2KX-3GP"
			(at -1.8923 -1.2065 0)
			(unlocked yes)
			(layer "B.Fab")
			(hide yes)
			(effects
				(font
					(size 1.016 1.016)
					(thickness 0.1524)
				)
				(justify mirror)
			)
		)
		(property "Device Type" "C402H22"
			(at -1.8923 -2.7305 0)
			(unlocked yes)
			(layer "B.Fab")
			(hide yes)
			(effects
				(font
					(size 1.016 1.016)
					(thickness 0.1524)
				)
				(justify mirror)
			)
		)
		(duplicate_pad_numbers_are_jumpers no)
		(fp_rect
			(start 0.381 0.7366)
			(end -0.381 -0.7366)
			(stroke
				(width 0)
				(type default)
			)
			(fill no)
			(layer "B.CrtYd")
		)
		(fp_rect
			(start 0.381 0.7366)
			(end -0.381 -0.7366)
			(stroke
				(width 0)
				(type default)
			)
			(fill no)
			(layer "B.Fab")
		)
		(pad "1" smd custom
			(at 0 -0.4572 180)
			(size 0.1143 0.1143)
			(layers "B.Cu" "B.Mask" "B.Paste")
			(net "PV_VDDR")
			(options
				(clearance outline)
				(anchor circle)
			)
			(primitives
				(gr_poly
					(pts
						(arc
							(start -0.254 0.1778)
							(mid -0.239121 0.213721)
							(end -0.2032 0.2286)
						)
						(arc
							(start 0.2032 0.2286)
							(mid 0.239121 0.213721)
							(end 0.254 0.1778)
						)
						(arc
							(start 0.254 -0.1778)
							(mid 0.239121 -0.213721)
							(end 0.2032 -0.2286)
						)
						(arc
							(start -0.2032 -0.2286)
							(mid -0.239121 -0.213721)
							(end -0.254 -0.1778)
						)
					)
					(width 0)
					(fill yes)
				)
			)
		)
		(pad "2" smd custom
			(at 0 0.4572 180)
			(size 0.1143 0.1143)
			(layers "B.Cu" "B.Mask" "B.Paste")
			(net "GND")
			(options
				(clearance outline)
				(anchor circle)
			)
			(primitives
				(gr_poly
					(pts
						(arc
							(start -0.254 0.1778)
							(mid -0.239121 0.213721)
							(end -0.2032 0.2286)
						)
						(arc
							(start 0.2032 0.2286)
							(mid 0.239121 0.213721)
							(end 0.254 0.1778)
						)
						(arc
							(start 0.254 -0.1778)
							(mid 0.239121 -0.213721)
							(end 0.2032 -0.2286)
						)
						(arc
							(start -0.2032 -0.2286)
							(mid -0.239121 -0.213721)
							(end -0.254 -0.1778)
						)
					)
					(width 0)
					(fill yes)
				)
			)
		)
	)
	(footprint ""
		(layer "B.Cu")
		(at 203.708 -64.0842 90)
		(property "Reference" "PC153"
			(at 0 0 90)
			(layer "B.SilkS")
			(hide yes)
			(effects
				(font
					(size 1.27 1.27)
				)
				(justify mirror)
			)
		)
		(property "Value" "SC10U6D3V3MX-GP"
			(at 0.0254 -2.0193 90)
			(unlocked yes)
			(layer "B.Fab")
			(hide yes)
			(effects
				(font
					(size 1.016 1.016)
					(thickness 0.1524)
				)
				(justify mirror)
			)
		)
		(property "Device Type" "C603H38"
			(at 0.0254 -3.5433 90)
			(unlocked yes)
			(layer "B.Fab")
			(hide yes)
			(effects
				(font
					(size 1.016 1.016)
					(thickness 0.1524)
				)
				(justify mirror)
			)
		)
		(duplicate_pad_numbers_are_jumpers no)
		(fp_line
			(start 0.4064 0)
			(end -0.4064 0)
			(stroke
				(width 0.2286)
				(type default)
			)
			(layer "B.SilkS")
		)
		(fp_rect
			(start 0.635 1.1811)
			(end -0.635 -1.1811)
			(stroke
				(width 0)
				(type default)
			)
			(fill no)
			(layer "B.CrtYd")
		)
		(fp_rect
			(start 0.635 1.1811)
			(end -0.635 -1.1811)
			(stroke
				(width 0)
				(type default)
			)
			(fill no)
			(layer "B.Fab")
		)
		(pad "1" smd custom
			(at 0 -0.6604 270)
			(size 0.19685 0.19685)
			(layers "B.Cu" "B.Mask" "B.Paste")
			(net "PV_VDDR")
			(options
				(clearance outline)
				(anchor circle)
			)
			(primitives
				(gr_poly
					(pts
						(arc
							(start 0.508 0.2921)
							(mid 0.478242 0.363942)
							(end 0.4064 0.3937)
						)
						(arc
							(start -0.4064 0.3937)
							(mid -0.478242 0.363942)
							(end -0.508 0.2921)
						)
						(arc
							(start -0.508 -0.2921)
							(mid -0.478242 -0.363942)
							(end -0.4064 -0.3937)
						)
						(arc
							(start 0.4064 -0.3937)
							(mid 0.478242 -0.363942)
							(end 0.508 -0.2921)
						)
					)
					(width 0)
					(fill yes)
				)
			)
		)
		(pad "2" smd custom
			(at 0 0.6604 270)
			(size 0.19685 0.19685)
			(layers "B.Cu" "B.Mask" "B.Paste")
			(net "GND")
			(options
				(clearance outline)
				(anchor circle)
			)
			(primitives
				(gr_poly
					(pts
						(arc
							(start 0.508 0.2921)
							(mid 0.478242 0.363942)
							(end 0.4064 0.3937)
						)
						(arc
							(start -0.4064 0.3937)
							(mid -0.478242 0.363942)
							(end -0.508 0.2921)
						)
						(arc
							(start -0.508 -0.2921)
							(mid -0.478242 -0.363942)
							(end -0.4064 -0.3937)
						)
						(arc
							(start 0.4064 -0.3937)
							(mid 0.478242 -0.363942)
							(end 0.508 -0.2921)
						)
					)
					(width 0)
					(fill yes)
				)
			)
		)
	)
	(footprint ""
		(layer "B.Cu")
		(at 43.3832 -16.7894)
		(property "Reference" "R355"
			(at 0 0 0)
			(layer "B.SilkS")
			(hide yes)
			(effects
				(font
					(size 1.27 1.27)
				)
				(justify mirror)
			)
		)
		(property "Value" "33R2F-3-GP"
			(at -0.064008 -3.993896 0)
			(unlocked yes)
			(layer "B.Fab")
			(hide yes)
			(effects
				(font
					(size 1.016 1.016)
					(thickness 0.1524)
				)
				(justify mirror)
			)
		)
		(property "Device Type" "R402H16"
			(at -0.064008 -5.517896 0)
			(unlocked yes)
			(layer "B.Fab")
			(hide yes)
			(effects
				(font
					(size 1.016 1.016)
					(thickness 0.1524)
				)
				(justify mirror)
			)
		)
		(duplicate_pad_numbers_are_jumpers no)
		(fp_rect
			(start 0.381 0.8382)
			(end -0.381 -0.8382)
			(stroke
				(width 0)
				(type default)
			)
			(fill no)
			(layer "B.CrtYd")
		)
		(fp_rect
			(start 0.381 0.8382)
			(end -0.381 -0.8382)
			(stroke
				(width 0)
				(type default)
			)
			(fill no)
			(layer "B.Fab")
		)
		(pad "1" smd custom
			(at 0 -0.4318 180)
			(size 0.127 0.127)
			(layers "B.Cu" "B.Mask" "B.Paste")
			(net "CLK_100M_CLKBUFF_ENET_R_DN")
			(options
				(clearance outline)
				(anchor circle)
			)
			(primitives
				(gr_poly
					(pts
						(arc
							(start -0.2032 0.2794)
							(mid -0.239121 0.264521)
							(end -0.254 0.2286)
						)
						(arc
							(start -0.254 -0.2286)
							(mid -0.239121 -0.264521)
							(end -0.2032 -0.2794)
						)
						(arc
							(start 0.2032 -0.2794)
							(mid 0.239121 -0.264521)
							(end 0.254 -0.2286)
						)
						(arc
							(start 0.254 0.2286)
							(mid 0.239121 0.264521)
							(end 0.2032 0.2794)
						)
					)
					(width 0)
					(fill yes)
				)
			)
		)
		(pad "2" smd custom
			(at 0 0.4318 180)
			(size 0.127 0.127)
			(layers "B.Cu" "B.Mask" "B.Paste")
			(net "CLK_100M_CLKBUFF_ENET_DN")
			(options
				(clearance outline)
				(anchor circle)
			)
			(primitives
				(gr_poly
					(pts
						(arc
							(start -0.2032 0.2794)
							(mid -0.239121 0.264521)
							(end -0.254 0.2286)
						)
						(arc
							(start -0.254 -0.2286)
							(mid -0.239121 -0.264521)
							(end -0.2032 -0.2794)
						)
						(arc
							(start 0.2032 -0.2794)
							(mid 0.239121 -0.264521)
							(end 0.254 -0.2286)
						)
						(arc
							(start 0.254 0.2286)
							(mid 0.239121 0.264521)
							(end 0.2032 0.2794)
						)
					)
					(width 0)
					(fill yes)
				)
			)
		)
	)
	(footprint ""
		(layer "B.Cu")
		(at 186.69 -31.6992)
		(property "Reference" "PR145"
			(at 0 0 0)
			(layer "B.SilkS")
			(hide yes)
			(effects
				(font
					(size 1.27 1.27)
				)
				(justify mirror)
			)
		)
		(property "Value" "8K45R2F-2-GP"
			(at -1.7907 -1.1176 0)
			(unlocked yes)
			(layer "B.Fab")
			(hide yes)
			(effects
				(font
					(size 1.016 1.016)
					(thickness 0.1524)
				)
				(justify mirror)
			)
		)
		(property "Device Type" "R402H16"
			(at -1.7907 -2.6416 0)
			(unlocked yes)
			(layer "B.Fab")
			(hide yes)
			(effects
				(font
					(size 1.016 1.016)
					(thickness 0.1524)
				)
				(justify mirror)
			)
		)
		(duplicate_pad_numbers_are_jumpers no)
		(fp_rect
			(start 0.381 0.8382)
			(end -0.381 -0.8382)
			(stroke
				(width 0)
				(type default)
			)
			(fill no)
			(layer "B.CrtYd")
		)
		(fp_rect
			(start 0.381 0.8382)
			(end -0.381 -0.8382)
			(stroke
				(width 0)
				(type default)
			)
			(fill no)
			(layer "B.Fab")
		)
		(pad "1" smd custom
			(at 0 -0.4318 180)
			(size 0.127 0.127)
			(layers "B.Cu" "B.Mask" "B.Paste")
			(net "VR_PVDDR_A_NTC")
			(options
				(clearance outline)
				(anchor circle)
			)
			(primitives
				(gr_poly
					(pts
						(arc
							(start -0.2032 0.2794)
							(mid -0.239121 0.264521)
							(end -0.254 0.2286)
						)
						(arc
							(start -0.254 -0.2286)
							(mid -0.239121 -0.264521)
							(end -0.2032 -0.2794)
						)
						(arc
							(start 0.2032 -0.2794)
							(mid 0.239121 -0.264521)
							(end 0.254 -0.2286)
						)
						(arc
							(start 0.254 0.2286)
							(mid 0.239121 0.264521)
							(end 0.2032 0.2794)
						)
					)
					(width 0)
					(fill yes)
				)
			)
		)
		(pad "2" smd custom
			(at 0 0.4318 180)
			(size 0.127 0.127)
			(layers "B.Cu" "B.Mask" "B.Paste")
			(net "VR_PVDDR_A_NTC_R")
			(options
				(clearance outline)
				(anchor circle)
			)
			(primitives
				(gr_poly
					(pts
						(arc
							(start -0.2032 0.2794)
							(mid -0.239121 0.264521)
							(end -0.254 0.2286)
						)
						(arc
							(start -0.254 -0.2286)
							(mid -0.239121 -0.264521)
							(end -0.2032 -0.2794)
						)
						(arc
							(start 0.2032 -0.2794)
							(mid 0.239121 -0.264521)
							(end 0.254 -0.2286)
						)
						(arc
							(start 0.254 0.2286)
							(mid 0.239121 0.264521)
							(end 0.2032 0.2794)
						)
					)
					(width 0)
					(fill yes)
				)
			)
		)
	)
	(footprint ""
		(layer "B.Cu")
		(at 203.073 -54.0512 90)
		(property "Reference" "PC157"
			(at 0 0 90)
			(layer "B.SilkS")
			(hide yes)
			(effects
				(font
					(size 1.27 1.27)
				)
				(justify mirror)
			)
		)
		(property "Value" "SC100U6D3V0MX-2GP"
			(at 2.3368 -3.5052 90)
			(unlocked yes)
			(layer "B.Fab")
			(hide yes)
			(effects
				(font
					(size 1.016 1.016)
					(thickness 0.1524)
				)
				(justify mirror)
			)
		)
		(property "Device Type" "C1210H107"
			(at 2.3368 -5.0292 90)
			(unlocked yes)
			(layer "B.Fab")
			(hide yes)
			(effects
				(font
					(size 1.016 1.016)
					(thickness 0.1524)
				)
				(justify mirror)
			)
		)
		(duplicate_pad_numbers_are_jumpers no)
		(fp_rect
			(start 1.4986 1.9685)
			(end -1.4986 -1.9685)
			(stroke
				(width 0)
				(type default)
			)
			(fill no)
			(layer "B.CrtYd")
		)
		(fp_rect
			(start 1.4986 1.9685)
			(end -1.4986 -1.9685)
			(stroke
				(width 0)
				(type default)
			)
			(fill no)
			(layer "B.Fab")
		)
		(pad "1" smd rect
			(at 0 -1.2446 270)
			(size 2.7432 1.1938)
			(layers "B.Cu" "B.Mask" "B.Paste")
			(net "PV_VDDR")
		)
		(pad "2" smd rect
			(at 0 1.2446 270)
			(size 2.7432 1.1938)
			(layers "B.Cu" "B.Mask" "B.Paste")
			(net "GND")
		)
	)
	(footprint ""
		(layer "B.Cu")
		(at 21.6408 -61.087)
		(property "Reference" "PC14"
			(at 0 0 0)
			(layer "B.SilkS")
			(hide yes)
			(effects
				(font
					(size 1.27 1.27)
				)
				(justify mirror)
			)
		)
		(property "Value" "SCD01U16V2KX-3GP"
			(at -1.8923 -1.2065 0)
			(unlocked yes)
			(layer "B.Fab")
			(hide yes)
			(effects
				(font
					(size 1.016 1.016)
					(thickness 0.1524)
				)
				(justify mirror)
			)
		)
		(property "Device Type" "C402H22"
			(at -1.8923 -2.7305 0)
			(unlocked yes)
			(layer "B.Fab")
			(hide yes)
			(effects
				(font
					(size 1.016 1.016)
					(thickness 0.1524)
				)
				(justify mirror)
			)
		)
		(duplicate_pad_numbers_are_jumpers no)
		(fp_rect
			(start 0.381 0.7366)
			(end -0.381 -0.7366)
			(stroke
				(width 0)
				(type default)
			)
			(fill no)
			(layer "B.CrtYd")
		)
		(fp_rect
			(start 0.381 0.7366)
			(end -0.381 -0.7366)
			(stroke
				(width 0)
				(type default)
			)
			(fill no)
			(layer "B.Fab")
		)
		(pad "1" smd custom
			(at 0 -0.4572 180)
			(size 0.1143 0.1143)
			(layers "B.Cu" "B.Mask" "B.Paste")
			(net "VR_PVNN_RTN")
			(options
				(clearance outline)
				(anchor circle)
			)
			(primitives
				(gr_poly
					(pts
						(arc
							(start -0.254 0.1778)
							(mid -0.239121 0.213721)
							(end -0.2032 0.2286)
						)
						(arc
							(start 0.2032 0.2286)
							(mid 0.239121 0.213721)
							(end 0.254 0.1778)
						)
						(arc
							(start 0.254 -0.1778)
							(mid 0.239121 -0.213721)
							(end 0.2032 -0.2286)
						)
						(arc
							(start -0.2032 -0.2286)
							(mid -0.239121 -0.213721)
							(end -0.254 -0.1778)
						)
					)
					(width 0)
					(fill yes)
				)
			)
		)
		(pad "2" smd custom
			(at 0 0.4572 180)
			(size 0.1143 0.1143)
			(layers "B.Cu" "B.Mask" "B.Paste")
			(net "GND")
			(options
				(clearance outline)
				(anchor circle)
			)
			(primitives
				(gr_poly
					(pts
						(arc
							(start -0.254 0.1778)
							(mid -0.239121 0.213721)
							(end -0.2032 0.2286)
						)
						(arc
							(start 0.2032 0.2286)
							(mid 0.239121 0.213721)
							(end 0.254 0.1778)
						)
						(arc
							(start 0.254 -0.1778)
							(mid 0.239121 -0.213721)
							(end 0.2032 -0.2286)
						)
						(arc
							(start -0.2032 -0.2286)
							(mid -0.239121 -0.213721)
							(end -0.254 -0.1778)
						)
					)
					(width 0)
					(fill yes)
				)
			)
		)
	)
)
